(kicad_pcb
	(version 20260206)
	(generator "pcbnew")
	(generator_version "10.0")
	(general
		(thickness 1.6)
		(legacy_teardrops no)
	)
	(paper "A4")
	(title_block
		(title "Bryce Canyon_F.DPB_16315-1-OCP.brd")
		(comment 1 "Bryce Canyon / footprints 1417-1423 of 2223")
	)
	(layers
		(0 "F.Cu" signal "TOP")
		(4 "In1.Cu" signal "L2GND")
		(6 "In2.Cu" signal "L3")
		(8 "In3.Cu" signal "L4GND")
		(10 "In4.Cu" signal "L5")
		(12 "In5.Cu" signal "L6VCC")
		(14 "In6.Cu" signal "L7VCC")
		(16 "In7.Cu" signal "L8")
		(18 "In8.Cu" signal "L9GND")
		(20 "In9.Cu" signal "L10")
		(22 "In10.Cu" signal "L11GND")
		(2 "B.Cu" signal "BOTTOM")
		(9 "F.Adhes" user "F.Adhesive")
		(11 "B.Adhes" user "B.Adhesive")
		(13 "F.Paste" user "Package Geometry/Pastemask Top")
		(15 "B.Paste" user "Package Geometry/Pastemask Bottom")
		(5 "F.SilkS" user "Ref Des/Silkscreen Top")
		(7 "B.SilkS" user "Ref Des/Silkscreen Bottom")
		(1 "F.Mask" user "Board Geometry/Soldermask Top")
		(3 "B.Mask" user "Board Geometry/Soldermask Bottom")
		(17 "Dwgs.User" user "User.Drawings")
		(19 "Cmts.User" user "User.Comments")
		(21 "Eco1.User" user "User.Eco1")
		(23 "Eco2.User" user "User.Eco2")
		(25 "Edge.Cuts" user "Board Geometry/Outline")
		(27 "Margin" user)
		(31 "F.CrtYd" user "Package Geometry/Place Bound Top")
		(29 "B.CrtYd" user "Package Geometry/Place Bound Bottom")
		(35 "F.Fab" user "Ref Des/Assembly Top")
		(33 "B.Fab" user "Ref Des/Assembly Bottom")
	)
	(footprint ""
		(layer "F.Cu")
		(at 441.964826 -242.25377)
		(property "Reference" "R266"
			(at 0 0 0)
			(layer "F.SilkS")
			(hide yes)
			(effects
				(font
					(size 1.27 1.27)
				)
			)
		)
		(property "Value" "91R3F-1-GP"
			(at -0.0254 -2.5146 0)
			(unlocked yes)
			(layer "F.Fab")
			(hide yes)
			(effects
				(font
					(size 1.016 1.016)
					(thickness 0.1524)
				)
			)
		)
		(property "Device Type" "R603H22"
			(at -0.0254 -4.0386 0)
			(unlocked yes)
			(layer "F.Fab")
			(hide yes)
			(effects
				(font
					(size 1.016 1.016)
					(thickness 0.1524)
				)
			)
		)
		(duplicate_pad_numbers_are_jumpers no)
		(fp_line
			(start -0.4826 0)
			(end -0.2032 0)
			(stroke
				(width 0.2032)
				(type default)
			)
			(layer "F.SilkS")
		)
		(fp_line
			(start 0.2032 0)
			(end 0.4826 0)
			(stroke
				(width 0.2032)
				(type default)
			)
			(layer "F.SilkS")
		)
		(fp_rect
			(start -0.5842 1.3335)
			(end 0.5842 -1.3335)
			(stroke
				(width 0)
				(type default)
			)
			(fill no)
			(layer "F.CrtYd")
		)
		(fp_rect
			(start -0.5842 1.3335)
			(end 0.5842 -1.3335)
			(stroke
				(width 0)
				(type default)
			)
			(fill no)
			(layer "F.Fab")
		)
		(pad "1" smd custom
			(at 0 -0.762)
			(size 0.2159 0.2159)
			(layers "F.Cu" "F.Mask" "F.Paste")
			(net "P5V_A_3")
			(options
				(clearance outline)
				(anchor circle)
			)
			(primitives
				(gr_poly
					(pts
						(arc
							(start -0.3302 -0.4318)
							(mid -0.402042 -0.402042)
							(end -0.4318 -0.3302)
						)
						(arc
							(start -0.4318 0.3302)
							(mid -0.402042 0.402042)
							(end -0.3302 0.4318)
						)
						(arc
							(start 0.3302 0.4318)
							(mid 0.402042 0.402042)
							(end 0.4318 0.3302)
						)
						(arc
							(start 0.4318 -0.3302)
							(mid 0.402042 -0.402042)
							(end 0.3302 -0.4318)
						)
					)
					(width 0)
					(fill yes)
				)
			)
		)
		(pad "2" smd custom
			(at 0 0.762)
			(size 0.2159 0.2159)
			(layers "F.Cu" "F.Mask" "F.Paste")
			(net "DRV_ACT_10")
			(options
				(clearance outline)
				(anchor circle)
			)
			(primitives
				(gr_poly
					(pts
						(arc
							(start -0.3302 -0.4318)
							(mid -0.402042 -0.402042)
							(end -0.4318 -0.3302)
						)
						(arc
							(start -0.4318 0.3302)
							(mid -0.402042 0.402042)
							(end -0.3302 0.4318)
						)
						(arc
							(start 0.3302 0.4318)
							(mid 0.402042 0.402042)
							(end 0.4318 0.3302)
						)
						(arc
							(start 0.4318 -0.3302)
							(mid 0.402042 -0.402042)
							(end 0.3302 -0.4318)
						)
					)
					(width 0)
					(fill yes)
				)
			)
		)
	)
	(footprint ""
		(layer "F.Cu")
		(at 130.828796 -65.064894 90)
		(property "Reference" "R755"
			(at 0 0 90)
			(layer "F.SilkS")
			(hide yes)
			(effects
				(font
					(size 1.27 1.27)
				)
			)
		)
		(property "Value" "220R3F-1-GP"
			(at -0.0254 -2.5146 90)
			(unlocked yes)
			(layer "F.Fab")
			(hide yes)
			(effects
				(font
					(size 1.016 1.016)
					(thickness 0.1524)
				)
			)
		)
		(property "Device Type" "R603H22"
			(at -0.0254 -4.0386 90)
			(unlocked yes)
			(layer "F.Fab")
			(hide yes)
			(effects
				(font
					(size 1.016 1.016)
					(thickness 0.1524)
				)
			)
		)
		(duplicate_pad_numbers_are_jumpers no)
		(fp_line
			(start 0.2032 0)
			(end 0.4826 0)
			(stroke
				(width 0.2032)
				(type default)
			)
			(layer "F.SilkS")
		)
		(fp_line
			(start -0.4826 0)
			(end -0.2032 0)
			(stroke
				(width 0.2032)
				(type default)
			)
			(layer "F.SilkS")
		)
		(fp_rect
			(start -0.5842 1.3335)
			(end 0.5842 -1.3335)
			(stroke
				(width 0)
				(type default)
			)
			(fill no)
			(layer "F.CrtYd")
		)
		(fp_rect
			(start -0.5842 1.3335)
			(end 0.5842 -1.3335)
			(stroke
				(width 0)
				(type default)
			)
			(fill no)
			(layer "F.Fab")
		)
		(pad "1" smd custom
			(at 0 -0.762 90)
			(size 0.2159 0.2159)
			(layers "F.Cu" "F.Mask" "F.Paste")
			(net "HDD_PRSNT_27")
			(options
				(clearance outline)
				(anchor circle)
			)
			(primitives
				(gr_poly
					(pts
						(arc
							(start -0.3302 -0.4318)
							(mid -0.402042 -0.402042)
							(end -0.4318 -0.3302)
						)
						(arc
							(start -0.4318 0.3302)
							(mid -0.402042 0.402042)
							(end -0.3302 0.4318)
						)
						(arc
							(start 0.3302 0.4318)
							(mid 0.402042 0.402042)
							(end 0.4318 0.3302)
						)
						(arc
							(start 0.4318 -0.3302)
							(mid 0.402042 -0.402042)
							(end 0.3302 -0.4318)
						)
					)
					(width 0)
					(fill yes)
				)
			)
		)
		(pad "2" smd custom
			(at 0 0.762 90)
			(size 0.2159 0.2159)
			(layers "F.Cu" "F.Mask" "F.Paste")
			(net "DRIVE_A_27_INS")
			(options
				(clearance outline)
				(anchor circle)
			)
			(primitives
				(gr_poly
					(pts
						(arc
							(start -0.3302 -0.4318)
							(mid -0.402042 -0.402042)
							(end -0.4318 -0.3302)
						)
						(arc
							(start -0.4318 0.3302)
							(mid -0.402042 0.402042)
							(end -0.3302 0.4318)
						)
						(arc
							(start 0.3302 0.4318)
							(mid 0.402042 0.402042)
							(end 0.4318 0.3302)
						)
						(arc
							(start 0.4318 -0.3302)
							(mid 0.402042 -0.402042)
							(end 0.3302 -0.4318)
						)
					)
					(width 0)
					(fill yes)
				)
			)
		)
	)
	(footprint ""
		(layer "F.Cu")
		(at 23.936198 -301.287942)
		(property "Reference" "C514"
			(at 0 0 0)
			(layer "F.SilkS")
			(hide yes)
			(effects
				(font
					(size 1.27 1.27)
				)
			)
		)
		(property "Value" "SC4D7U25V5KX-1-GP"
			(at -0.0762 -6.1214 0)
			(unlocked yes)
			(layer "F.Fab")
			(hide yes)
			(effects
				(font
					(size 1.016 1.016)
					(thickness 0.1524)
				)
			)
		)
		(property "Device Type" "C805H58"
			(at -0.0762 -8.1534 0)
			(unlocked yes)
			(layer "F.Fab")
			(hide yes)
			(effects
				(font
					(size 1.016 1.016)
					(thickness 0.1524)
				)
			)
		)
		(duplicate_pad_numbers_are_jumpers no)
		(fp_line
			(start 0.635 0)
			(end -0.635 0)
			(stroke
				(width 0.508)
				(type default)
			)
			(layer "F.SilkS")
		)
		(fp_rect
			(start -0.9652 1.778)
			(end 0.9652 -1.778)
			(stroke
				(width 0)
				(type default)
			)
			(fill no)
			(layer "F.CrtYd")
		)
		(fp_poly
			(pts
				(xy -0.9652 -1.778) (xy 0.9652 -1.778) (xy 0.9652 1.778) (xy -0.9652 1.778)
			)
			(stroke
				(width 0)
				(type default)
			)
			(fill no)
			(layer "F.Fab")
		)
		(pad "1" smd rect
			(at 0 -0.9652)
			(size 1.397 1.143)
			(layers "F.Cu" "F.Mask" "F.Paste")
			(net "P12V_HDD0")
		)
		(pad "2" smd rect
			(at 0 0.9652)
			(size 1.397 1.143)
			(layers "F.Cu" "F.Mask" "F.Paste")
			(net "GND")
		)
	)
	(footprint ""
		(layer "F.Cu")
		(at 471.603324 -283.818076 90)
		(property "Reference" "C192"
			(at 0 0 90)
			(layer "F.SilkS")
			(hide yes)
			(effects
				(font
					(size 1.27 1.27)
				)
			)
		)
		(property "Value" "SCD033U25V2KX-GP"
			(at 1.1811 -2.7051 90)
			(unlocked yes)
			(layer "F.Fab")
			(hide yes)
			(effects
				(font
					(size 1.016 1.016)
					(thickness 0.1524)
				)
			)
		)
		(property "Device Type" "C402H22"
			(at 1.1811 -4.2291 90)
			(unlocked yes)
			(layer "F.Fab")
			(hide yes)
			(effects
				(font
					(size 1.016 1.016)
					(thickness 0.1524)
				)
			)
		)
		(duplicate_pad_numbers_are_jumpers no)
		(fp_rect
			(start -0.4318 0.9525)
			(end 0.4318 -0.9525)
			(stroke
				(width 0)
				(type default)
			)
			(fill no)
			(layer "F.CrtYd")
		)
		(fp_rect
			(start -0.4318 0.9525)
			(end 0.4318 -0.9525)
			(stroke
				(width 0)
				(type default)
			)
			(fill no)
			(layer "F.Fab")
		)
		(pad "1" smd custom
			(at 0 -0.4445 90)
			(size 0.1524 0.1524)
			(layers "F.Cu" "F.Mask" "F.Paste")
			(net "P12V_A")
			(options
				(clearance outline)
				(anchor circle)
			)
			(primitives
				(gr_poly
					(pts
						(arc
							(start 0.3048 -0.2032)
							(mid 0.275042 -0.275042)
							(end 0.2032 -0.3048)
						)
						(arc
							(start -0.2032 -0.3048)
							(mid -0.275042 -0.275042)
							(end -0.3048 -0.2032)
						)
						(arc
							(start -0.3048 0.2032)
							(mid -0.275042 0.275042)
							(end -0.2032 0.3048)
						)
						(arc
							(start 0.2032 0.3048)
							(mid 0.275042 0.275042)
							(end 0.3048 0.2032)
						)
					)
					(width 0)
					(fill yes)
				)
			)
		)
		(pad "2" smd custom
			(at 0 0.4445 90)
			(size 0.1524 0.1524)
			(layers "F.Cu" "F.Mask" "F.Paste")
			(net "SW_HDD_N11")
			(options
				(clearance outline)
				(anchor circle)
			)
			(primitives
				(gr_poly
					(pts
						(arc
							(start 0.3048 -0.2032)
							(mid 0.275042 -0.275042)
							(end 0.2032 -0.3048)
						)
						(arc
							(start -0.2032 -0.3048)
							(mid -0.275042 -0.275042)
							(end -0.3048 -0.2032)
						)
						(arc
							(start -0.3048 0.2032)
							(mid -0.275042 0.275042)
							(end -0.2032 0.3048)
						)
						(arc
							(start 0.2032 0.3048)
							(mid 0.275042 0.275042)
							(end 0.3048 0.2032)
						)
					)
					(width 0)
					(fill yes)
				)
			)
		)
	)
	(footprint ""
		(layer "F.Cu")
		(at 319.786 -42.627042 180)
		(property "Reference" "VIA69"
			(at 0 0 180)
			(layer "F.SilkS")
			(hide yes)
			(effects
				(font
					(size 1.27 1.27)
				)
			)
		)
		(property "Value" "100OHM-8L-1D6MM-L18L16-GP"
			(at -3.7211 -4.5085 180)
			(unlocked yes)
			(layer "F.Fab")
			(hide yes)
			(effects
				(font
					(size 1.016 1.016)
					(thickness 0.1524)
				)
			)
		)
		(property "Device Type" "VIA-PCIE-4P-394076"
			(at -3.7211 -6.0325 180)
			(unlocked yes)
			(layer "F.Fab")
			(hide yes)
			(effects
				(font
					(size 1.016 1.016)
					(thickness 0.1524)
				)
			)
		)
		(duplicate_pad_numbers_are_jumpers no)
		(fp_rect
			(start -1.9685 0.381)
			(end 1.9685 -0.381)
			(stroke
				(width 0)
				(type default)
			)
			(fill no)
			(layer "F.CrtYd")
		)
		(fp_rect
			(start -1.9685 0.381)
			(end 1.9685 -0.381)
			(stroke
				(width 0)
				(type default)
			)
			(fill no)
			(layer "F.Fab")
		)
		(pad "1" thru_hole circle
			(at -1.5875 0 180)
			(size 0.508 0.508)
			(drill 0.254)
			(layers "*.Cu" "*.Mask")
			(remove_unused_layers no)
			(net "GND")
			(clearance 0.127)
			(thermal_gap 0.127)
		)
		(pad "2" thru_hole circle
			(at -0.5715 0 180)
			(size 0.508 0.508)
			(drill 0.254)
			(layers "*.Cu" "*.Mask")
			(remove_unused_layers no)
			(net "PHY_SCC_A_TO_DRV_A_30_DP")
			(clearance 0.127)
			(thermal_gap 0.127)
		)
		(pad "3" thru_hole circle
			(at 0.5715 0 180)
			(size 0.508 0.508)
			(drill 0.254)
			(layers "*.Cu" "*.Mask")
			(remove_unused_layers no)
			(net "PHY_SCC_A_TO_DRV_A_30_DN")
			(clearance 0.127)
			(thermal_gap 0.127)
		)
		(pad "4" thru_hole circle
			(at 1.5875 0 180)
			(size 0.508 0.508)
			(drill 0.254)
			(layers "*.Cu" "*.Mask")
			(remove_unused_layers no)
			(net "GND")
			(clearance 0.127)
			(thermal_gap 0.127)
		)
	)
	(footprint ""
		(layer "F.Cu")
		(at 34.397188 -304.428398 180)
		(property "Reference" "R210"
			(at 0 0 180)
			(layer "F.SilkS")
			(hide yes)
			(effects
				(font
					(size 1.27 1.27)
				)
			)
		)
		(property "Value" "91R3F-1-GP"
			(at -0.0254 -2.5146 180)
			(unlocked yes)
			(layer "F.Fab")
			(hide yes)
			(effects
				(font
					(size 1.016 1.016)
					(thickness 0.1524)
				)
			)
		)
		(property "Device Type" "R603H22"
			(at -0.0254 -4.0386 180)
			(unlocked yes)
			(layer "F.Fab")
			(hide yes)
			(effects
				(font
					(size 1.016 1.016)
					(thickness 0.1524)
				)
			)
		)
		(duplicate_pad_numbers_are_jumpers no)
		(fp_line
			(start 0.2032 0)
			(end 0.4826 0)
			(stroke
				(width 0.2032)
				(type default)
			)
			(layer "F.SilkS")
		)
		(fp_line
			(start -0.4826 0)
			(end -0.2032 0)
			(stroke
				(width 0.2032)
				(type default)
			)
			(layer "F.SilkS")
		)
		(fp_rect
			(start -0.5842 1.3335)
			(end 0.5842 -1.3335)
			(stroke
				(width 0)
				(type default)
			)
			(fill no)
			(layer "F.CrtYd")
		)
		(fp_rect
			(start -0.5842 1.3335)
			(end 0.5842 -1.3335)
			(stroke
				(width 0)
				(type default)
			)
			(fill no)
			(layer "F.Fab")
		)
		(pad "1" smd custom
			(at 0 -0.762 180)
			(size 0.2159 0.2159)
			(layers "F.Cu" "F.Mask" "F.Paste")
			(net "P5V_B")
			(options
				(clearance outline)
				(anchor circle)
			)
			(primitives
				(gr_poly
					(pts
						(arc
							(start -0.3302 -0.4318)
							(mid -0.402042 -0.402042)
							(end -0.4318 -0.3302)
						)
						(arc
							(start -0.4318 0.3302)
							(mid -0.402042 0.402042)
							(end -0.3302 0.4318)
						)
						(arc
							(start 0.3302 0.4318)
							(mid 0.402042 0.402042)
							(end 0.4318 0.3302)
						)
						(arc
							(start 0.4318 -0.3302)
							(mid 0.402042 -0.402042)
							(end 0.3302 -0.4318)
						)
					)
					(width 0)
					(fill yes)
				)
			)
		)
		(pad "2" smd custom
			(at 0 0.762 180)
			(size 0.2159 0.2159)
			(layers "F.Cu" "F.Mask" "F.Paste")
			(net "DRV_ACT_25")
			(options
				(clearance outline)
				(anchor circle)
			)
			(primitives
				(gr_poly
					(pts
						(arc
							(start -0.3302 -0.4318)
							(mid -0.402042 -0.402042)
							(end -0.4318 -0.3302)
						)
						(arc
							(start -0.4318 0.3302)
							(mid -0.402042 0.402042)
							(end -0.3302 0.4318)
						)
						(arc
							(start 0.3302 0.4318)
							(mid 0.402042 0.402042)
							(end 0.4318 0.3302)
						)
						(arc
							(start 0.4318 -0.3302)
							(mid 0.402042 -0.402042)
							(end 0.3302 -0.4318)
						)
					)
					(width 0)
					(fill yes)
				)
			)
		)
	)
	(footprint ""
		(layer "F.Cu")
		(at 172.593 -289.857942)
		(property "Reference" "Q32"
			(at 0 0 0)
			(layer "F.SilkS")
			(hide yes)
			(effects
				(font
					(size 1.27 1.27)
				)
			)
		)
		(property "Value" "AO4407AL-GP"
			(at -3.707384 -1.5367 0)
			(unlocked yes)
			(layer "F.Fab")
			(hide yes)
			(effects
				(font
					(size 1.016 1.016)
					(thickness 0.1524)
				)
			)
		)
		(property "Device Type" "SOIC8H69"
			(at -3.707384 -3.0607 0)
			(unlocked yes)
			(layer "F.Fab")
			(hide yes)
			(effects
				(font
					(size 1.016 1.016)
					(thickness 0.1524)
				)
			)
		)
		(duplicate_pad_numbers_are_jumpers no)
		(fp_line
			(start -2.7432 -1.4224)
			(end -2.7432 1.4224)
			(stroke
				(width 0.1524)
				(type default)
			)
			(layer "F.SilkS")
		)
		(fp_line
			(start -2.7432 1.4224)
			(end -2.6416 1.4224)
			(stroke
				(width 0.1524)
				(type default)
			)
			(layer "F.SilkS")
		)
		(fp_line
			(start -2.7432 1.4224)
			(end 2.1336 1.4224)
			(stroke
				(width 0.1524)
				(type default)
			)
			(layer "F.SilkS")
		)
		(fp_line
			(start -2.7178 -0.508)
			(end -2.1844 -0.0508)
			(stroke
				(width 0.1524)
				(type default)
			)
			(layer "F.SilkS")
		)
		(fp_line
			(start -2.6289 3.4417)
			(end -2.6289 1.4732)
			(stroke
				(width 0.381)
				(type default)
			)
			(layer "F.SilkS")
		)
		(fp_line
			(start -2.1844 -0.0508)
			(end -2.7178 0.508)
			(stroke
				(width 0.1524)
				(type default)
			)
			(layer "F.SilkS")
		)
		(fp_line
			(start 2.1336 -1.4224)
			(end -2.7432 -1.4224)
			(stroke
				(width 0.1524)
				(type default)
			)
			(layer "F.SilkS")
		)
		(fp_line
			(start 2.1336 1.4224)
			(end 2.1336 -1.4224)
			(stroke
				(width 0.1524)
				(type default)
			)
			(layer "F.SilkS")
		)
		(fp_poly
			(pts
				(xy -2.2098 -1.4224) (xy -2.2098 1.4224) (xy 2.2098 1.4224) (xy 2.2098 -1.4224)
			)
			(stroke
				(width 0)
				(type default)
			)
			(fill yes)
			(layer "F.SilkS")
		)
		(fp_rect
			(start -2.450084 2.999994)
			(end 2.450084 -2.999994)
			(stroke
				(width 0)
				(type default)
			)
			(fill no)
			(layer "F.CrtYd")
		)
		(fp_poly
			(pts
				(xy -2.8194 3.6322) (xy -2.8194 -3.6322) (xy 2.8194 -3.6322) (xy 2.8194 1.18364) (xy 2.450084 1.18364)
				(xy 2.450084 -2.999994) (xy -2.450084 -2.999994) (xy -2.450084 2.999994) (xy 2.450084 2.999994)
				(xy 2.450084 1.18618) (xy 2.8194 1.18618) (xy 2.8194 3.6322)
			)
			(stroke
				(width 0)
				(type default)
			)
			(fill no)
			(layer "F.CrtYd")
		)
		(fp_rect
			(start -2.8194 3.6322)
			(end 2.8194 -3.6322)
			(stroke
				(width 0)
				(type default)
			)
			(fill no)
			(layer "F.Fab")
		)
		(pad "1" smd rect
			(at -1.905 2.54)
			(size 0.635 1.651)
			(layers "F.Cu" "F.Mask" "F.Paste")
			(net "P12V_A")
		)
		(pad "2" smd rect
			(at -0.635 2.54)
			(size 0.635 1.651)
			(layers "F.Cu" "F.Mask" "F.Paste")
			(net "P12V_A")
		)
		(pad "3" smd rect
			(at 0.635 2.54)
			(size 0.635 1.651)
			(layers "F.Cu" "F.Mask" "F.Paste")
			(net "P12V_A")
		)
		(pad "4" smd rect
			(at 1.905 2.54)
			(size 0.635 1.651)
			(layers "F.Cu" "F.Mask" "F.Paste")
			(net "SW_HDD_N5")
		)
		(pad "5" smd rect
			(at 1.905 -2.54)
			(size 0.635 1.651)
			(layers "F.Cu" "F.Mask" "F.Paste")
			(net "P12V_HDD5")
		)
		(pad "6" smd rect
			(at 0.635 -2.54)
			(size 0.635 1.651)
			(layers "F.Cu" "F.Mask" "F.Paste")
			(net "P12V_HDD5")
		)
		(pad "7" smd rect
			(at -0.635 -2.54)
			(size 0.635 1.651)
			(layers "F.Cu" "F.Mask" "F.Paste")
			(net "P12V_HDD5")
		)
		(pad "8" smd rect
			(at -1.905 -2.54)
			(size 0.635 1.651)
			(layers "F.Cu" "F.Mask" "F.Paste")
			(net "P12V_HDD5")
		)
	)
)
